FILE_TYPE = CONNECTIVITY;
{Allegro Design Entry HDL 17.2-2016 S081 (4005846) 1/11/2022}
"PAGE_NUMBER" = 243;
0"NC";
1"P3V3_AUX\g";
2"PGPPA_AUX\g";
3"PGPPA_AUX\g";
4"P1V8_PCH_AUX\g";
5"P3V3_AUX\g";
6"GND\g";
7"GND\g";
8"GND\g";
9"FM_LPC_ESPI_SEL"CDS_PHYS_NET_NAME"FM_LPC_ESPI_SEL";
10"FM_ESPI_PLD_R_EN_BUF_R"CDS_PHYS_NET_NAME"FM_ESPI_PLD_R_EN_BUF";
11"FM_ESPI_PLD_R_EN_BUF"CDS_PHYS_NET_NAME"FM_ESPI_PLD_R_EN_BUF";
%"VCC15"
"1","(-4675,14225)","0","logical_power","I1";
;
HDL_POWER"P1V8_PCH_AUX"
BOM_COST"VR_SYSTEM "
CDS_LIB"logical_power";
"A"4;
%"UNIVERSAL_GND"
"1","(-4000,12125)","0","logical_power","I11";
;
HDL_POWER"GND"
CDS_LIB"logical_power";
"A"8;
%"UNIVERSAL_POWER"
"1","(-4125,11725)","0","logical_power","I12";
;
HDL_POWER"P3V3_AUX"
BOM_COST"VR_SYSTEM "
CDS_LIB"logical_power";
"A"5;
%"Q_RES"
"2","(-4675,11800)","0","pure_quanta","I13";
;
PART_NUMBER"CS00004JA05"
VALUE"0"
TOLERANCE"5%"
WATTAGE"1/8W"
PACK_TYPE"0805LF"
MATERIAL"EMPTY"
$LOCATION"R1765"
CDS_LIB"pure_quanta"
CDS_LOCATION"R1765"
$SEC"1"
CDS_SEC"1";
"A"
$PN"1"3;
"B"
$PN"2"5;
%"MOSFET_N"
"1","(-8450,12800)","2","pure_quanta","I15";
;
PART_NUMBER"BAM138K0000"
MANUF_PN"BSS138K"
VALUE"BSS138K"
MATERIAL"IC"
$LOCATION"U307"
CDS_LMAN_SYM_OUTLINE"-50,50,100,-150"
CDS_LIB"pure_quanta"
PACK_TYPE"SMLF"
CDS_LOCATION"U307"
$SEC"1"
CDS_SEC"1";
"GATE"
$PN"G"10;
"SOURCE"
$PN"S"7;
"DRAIN"
$PN"D"9;
%"Q_RES"
"2","(-8500,13250)","0","pure_quanta","I16";
;
PART_NUMBER"CS31002FB08"
TOLERANCE"1%"
PACK_TYPE"0402LF"
MATERIAL"CHIP"
WATTAGE"1/16W"
VALUE"10K"
$LOCATION"R4176"
CDS_LIB"pure_quanta"
CDS_LOCATION"R4176"
$SEC"1"
CDS_SEC"1";
"A"
$PN"1"1;
"B"
$PN"2"9;
%"UNIVERSAL_POWER"
"1","(-8500,13550)","0","logical_power","I17";
;
HDL_POWER"P3V3_AUX"
CDS_LIB"logical_power"
BOM_COST"VR_SYSTEM ";
"A"1;
%"UNIVERSAL_GND"
"1","(-8500,12350)","0","logical_power","I18";
;
CDS_LIB"logical_power"
HDL_POWER"GND";
"A"7;
%"Q_RES"
"1","(-7375,12700)","0","pure_quanta","I19";
;
PART_NUMBER"CS00002JB13"
MATERIAL"CHIP"
VALUE"0"
TOLERANCE"5%"
$LOCATION"R4177"
WATTAGE"1/16W"
PACK_TYPE"0402LF"
CDS_LIB"pure_quanta"
CDS_LOCATION"R4177"
$SEC"1"
CDS_SEC"1";
"B"
$PN"2"11;
"A"
$PN"1"10;
%"Q_RES"
"2","(-4675,13625)","0","pure_quanta","I2";
;
PART_NUMBER"CS00004JA05"
PACK_TYPE"0805LF"
TOLERANCE"5%"
MATERIAL"CHIP"
WATTAGE"1/8W"
VALUE"0"
$LOCATION"R1747"
CDS_LIB"pure_quanta"
CDS_LOCATION"R1747"
$SEC"1"
CDS_SEC"1";
"A"
$PN"1"4;
"B"
$PN"2"3;
%"UNIVERSAL_POWER"
"1","(-4000,12825)","0","logical_power","I3";
;
HDL_POWER"PGPPA_AUX"
CDS_LIB"logical_power"
BOM_COST"VR_SYSTEM ";
"A"3;
%"Q_CAP"
"1","(-4000,12450)","0","pure_quanta","I4";
;
PART_NUMBER"CH6223MEA01"
MATERIAL"X6S"
TOLERANCE"20%"
VOLTAGE"16V"
VALUE"22UF"
PACK_TYPE"C0805"
$LOCATION"C535"
CDS_LIB"pure_quanta"
CDS_LOCATION"C535"
$SEC"1"
CDS_SEC"1";
"B"
$PN"2"8;
"A"
$PN"1"3;
%"Q_CAP"
"1","(-4475,12450)","0","pure_quanta","I5";
;
PART_NUMBER"CH6223MEA01"
PACK_TYPE"C0805"
TOLERANCE"20%"
VALUE"22UF"
VOLTAGE"16V"
MATERIAL"X6S"
$LOCATION"C513"
CDS_LIB"pure_quanta"
CDS_LOCATION"C513"
$SEC"1"
CDS_SEC"1";
"B"
$PN"2"8;
"A"
$PN"1"3;
%"UNIVERSAL_POWER"
"1","(-9200,13550)","0","logical_power","I6";
;
HDL_POWER"PGPPA_AUX"
BOM_COST"VR_SYSTEM "
CDS_LIB"logical_power";
"A"2;
%"Q_RES"
"2","(-9200,13250)","0","pure_quanta","I7";
;
PART_NUMBER"CS31002FB08"
WATTAGE"1/16W"
TOLERANCE"1%"
VALUE"10K"
PACK_TYPE"0402LF"
MATERIAL"EMPTY"
$LOCATION"R1763"
CDS_LIB"pure_quanta"
CDS_LOCATION"R1763"
$SEC"1"
CDS_SEC"1";
"A"
$PN"1"2;
"B"
$PN"2"9;
%"Q_RES"
"2","(-9200,12650)","0","pure_quanta","I8";
;
PART_NUMBER"CS21002FB06"
MATERIAL"EMPTY"
VALUE"1K"
WATTAGE"1/16W"
TOLERANCE"1%"
PACK_TYPE"0402LF"
$LOCATION"R1764"
CDS_LIB"pure_quanta"
CDS_LOCATION"R1764"
$SEC"1"
CDS_SEC"1";
"A"
$PN"1"9;
"B"
$PN"2"6;
%"UNIVERSAL_GND"
"1","(-9200,12300)","0","logical_power","I9";
;
HDL_POWER"GND"
CDS_LIB"logical_power";
"A"6;
END.
